(kicad_pcb
	(version 20260206)
	(generator "pcbnew")
	(generator_version "10.0")
	(general
		(thickness 1.5755)
		(legacy_teardrops no)
	)
	(paper "A4")
	(title_block
		(title "gnss-rcb-f9t — GPS_MODULE_ZED-F9T.PcbDoc")
		(comment 1 "Time Appliance Project (Time Card) / footprints 28-30 of 44")
	)
	(layers
		(0 "F.Cu" signal "Top Layer")
		(4 "In1.Cu" signal "Int1 (GND)")
		(6 "In2.Cu" signal "Int2 (GND)")
		(2 "B.Cu" signal "Bottom Layer")
		(9 "F.Adhes" user "F.Adhesive")
		(11 "B.Adhes" user "B.Adhesive")
		(13 "F.Paste" user "Top Paste")
		(15 "B.Paste" user "Bottom Paste")
		(5 "F.SilkS" user "Top Overlay")
		(7 "B.SilkS" user "Bottom Overlay")
		(1 "F.Mask" user "Top Solder")
		(3 "B.Mask" user "Bottom Solder")
		(17 "Dwgs.User" user "User.Drawings")
		(19 "Cmts.User" user "User.Comments")
		(21 "Eco1.User" user "User.Eco1")
		(23 "Eco2.User" user "User.Eco2")
		(25 "Edge.Cuts" user)
		(27 "Margin" user)
		(31 "F.CrtYd" user "Top Courtyard")
		(29 "B.CrtYd" user "Bottom Courtyard")
		(35 "F.Fab" user "Top Component Outline")
		(33 "B.Fab" user "Bottom Component Outline")
	)
	(footprint "Vault:LEDS160X80X110-2N_LXFM0603-GR"
		(layer "F.Cu")
		(at 178.1865 100.2259 -90)
		(property "Reference" "DS1"
			(at -3.29946 -0.00287 90)
			(unlocked yes)
			(layer "F.SilkS")
			(effects
				(font
					(size 0.8 0.8)
					(thickness 0.14986)
				)
			)
		)
		(property "Value" "Lumex_SML-LXFM0603SUGCTR"
			(at 3.318002 -17.78687 0)
			(unlocked yes)
			(layer "F.SilkS")
			(hide yes)
			(effects
				(font
					(size 1.524 1.524)
					(thickness 0.254)
				)
			)
		)
		(sheetname "ZED-F9T")
		(sheetfile "ZED-F9T.kicad_sch")
		(duplicate_pad_numbers_are_jumpers no)
		(fp_line
			(start -1.6 0.3)
			(end -1.6 -0.3)
			(stroke
				(width 0.1)
				(type solid)
			)
			(layer "F.SilkS")
		)
		(fp_line
			(start -1.7 0.7)
			(end -1.7 -0.7)
			(stroke
				(width 0.1)
				(type solid)
			)
			(layer "F.CrtYd")
		)
		(fp_line
			(start 1.7 0.7)
			(end -1.7 0.7)
			(stroke
				(width 0.1)
				(type solid)
			)
			(layer "F.CrtYd")
		)
		(fp_line
			(start 1.7 0.7)
			(end 1.7 -0.7)
			(stroke
				(width 0.1)
				(type solid)
			)
			(layer "F.CrtYd")
		)
		(fp_line
			(start 1.7 -0.7)
			(end -1.7 -0.7)
			(stroke
				(width 0.1)
				(type solid)
			)
			(layer "F.CrtYd")
		)
		(fp_line
			(start -0.79991 0.39983)
			(end -0.79991 -0.40013)
			(stroke
				(width 0.05)
				(type solid)
			)
			(layer "F.Fab")
		)
		(fp_line
			(start 0.80017 0.39983)
			(end -0.79991 0.39983)
			(stroke
				(width 0.05)
				(type solid)
			)
			(layer "F.Fab")
		)
		(fp_line
			(start 0.80017 0.39983)
			(end 0.80017 -0.40013)
			(stroke
				(width 0.05)
				(type solid)
			)
			(layer "F.Fab")
		)
		(fp_line
			(start -0.1 0.3)
			(end -0.1 -0.3)
			(stroke
				(width 0.05)
				(type solid)
			)
			(layer "F.Fab")
		)
		(fp_line
			(start 0.1 0.2)
			(end -0.1 0)
			(stroke
				(width 0.05)
				(type solid)
			)
			(layer "F.Fab")
		)
		(fp_line
			(start 0.1 0.2)
			(end 0.1 -0.2)
			(stroke
				(width 0.05)
				(type solid)
			)
			(layer "F.Fab")
		)
		(fp_line
			(start -0.1 0)
			(end 0.1 -0.2)
			(stroke
				(width 0.05)
				(type solid)
			)
			(layer "F.Fab")
		)
		(fp_line
			(start 0.80017 -0.40013)
			(end -0.79991 -0.40013)
			(stroke
				(width 0.05)
				(type solid)
			)
			(layer "F.Fab")
		)
		(fp_text_box "${REFERENCE}"
			(start -2.76472 -0.52514)
			(end 2.76472 0.52513)
			(margins 0 0 0 0)
			(layer "F.Fab")
			(effects
				(font
					(face "Arial")
					(size 0.8001 0.8001)
					(thickness 0.254)
				)
				(justify top)
			)
			(border no)
			(stroke
				(width 0.1)
				(type default)
			)
			(knockout no)
		)
		(pad "A" smd rect
			(at 0.825 0 270)
			(size 0.8 0.8)
			(layers "F.Cu" "F.Mask" "F.Paste")
			(net "TP2")
			(solder_mask_margin 0.05)
			(solder_paste_margin 0)
		)
		(pad "K" smd rect
			(at -0.825 0 270)
			(size 0.8 0.8)
			(layers "F.Cu" "F.Mask" "F.Paste")
			(net "NetDS1_K")
			(solder_mask_margin 0.05)
			(solder_paste_margin 0)
		)
	)
	(footprint "GNSS_Receiver_Library:GPS_ZED-F9T"
		(locked yes)
		(layer "F.Cu")
		(at 139.25811 100.0441 -90)
		(property "Reference" "U1"
			(at -3.39673 1.58701 0)
			(unlocked yes)
			(layer "F.SilkS")
			(effects
				(font
					(size 0.8 0.8)
					(thickness 0.15)
				)
			)
		)
		(property "Value" "ZED-F9T-00B"
			(at 17.651602 -5.494845 0)
			(unlocked yes)
			(layer "F.SilkS")
			(hide yes)
			(effects
				(font
					(size 1.524 1.524)
					(thickness 0.254)
				)
			)
		)
		(sheetname "ZED-F9T")
		(sheetfile "ZED-F9T.kicad_sch")
		(duplicate_pad_numbers_are_jumpers no)
		(fp_circle
			(center 0.05 2.4)
			(end -0.0262 2.4)
			(stroke
				(width 0.762)
				(type solid)
			)
			(fill no)
			(layer "F.SilkS")
		)
		(pad "1" smd rect
			(at 0 0 270)
			(size 0.8 1.5)
			(layers "F.Cu" "F.Mask" "F.Paste")
			(net "GND")
		)
		(pad "2" smd rect
			(at 1.1 0 270)
			(size 0.8 1.5)
			(layers "F.Cu" "F.Mask" "F.Paste")
			(net "RF_IN")
		)
		(pad "3" smd rect
			(at 2.2 0 270)
			(size 0.8 1.5)
			(layers "F.Cu" "F.Mask" "F.Paste")
			(net "GND")
		)
		(pad "4" smd rect
			(at 3.3 0 270)
			(size 0.8 1.5)
			(layers "F.Cu" "F.Mask" "F.Paste")
			(net "ANT_DET")
		)
		(pad "5" smd rect
			(at 4.4 0 270)
			(size 0.8 1.5)
			(layers "F.Cu" "F.Mask" "F.Paste")
			(net "ANT_OFF")
		)
		(pad "6" smd rect
			(at 5.5 0 270)
			(size 0.8 1.5)
			(layers "F.Cu" "F.Mask" "F.Paste")
			(net "ANT_SHORT_N")
		)
		(pad "7" smd rect
			(at 6.6 0 270)
			(size 0.8 1.5)
			(layers "F.Cu" "F.Mask" "F.Paste")
		)
		(pad "8" smd rect
			(at 7.7 0 270)
			(size 0.8 1.5)
			(layers "F.Cu" "F.Mask" "F.Paste")
		)
		(pad "9" smd rect
			(at 8.8 0 270)
			(size 0.8 1.5)
			(layers "F.Cu" "F.Mask" "F.Paste")
		)
		(pad "10" smd rect
			(at 9.9 0 270)
			(size 0.8 1.5)
			(layers "F.Cu" "F.Mask" "F.Paste")
		)
		(pad "11" smd rect
			(at 11 0 270)
			(size 0.8 1.5)
			(layers "F.Cu" "F.Mask" "F.Paste")
		)
		(pad "12" smd rect
			(at 12.1 0 270)
			(size 0.8 1.5)
			(layers "F.Cu" "F.Mask" "F.Paste")
			(net "GND")
		)
		(pad "13" smd rect
			(at 13.2 0 270)
			(size 0.8 1.5)
			(layers "F.Cu" "F.Mask" "F.Paste")
		)
		(pad "14" smd rect
			(at 14.3 0 270)
			(size 0.8 1.5)
			(layers "F.Cu" "F.Mask" "F.Paste")
			(net "GND")
		)
		(pad "15" smd rect
			(at 17.1 -0.85)
			(size 0.8 1.5)
			(layers "F.Cu" "F.Mask" "F.Paste")
		)
		(pad "16" smd rect
			(at 17.1 -1.95)
			(size 0.8 1.5)
			(layers "F.Cu" "F.Mask" "F.Paste")
		)
		(pad "17" smd rect
			(at 17.1 -3.05)
			(size 0.8 1.5)
			(layers "F.Cu" "F.Mask" "F.Paste")
		)
		(pad "18" smd rect
			(at 17.1 -4.15)
			(size 0.8 1.5)
			(layers "F.Cu" "F.Mask" "F.Paste")
		)
		(pad "19" smd rect
			(at 17.1 -5.25)
			(size 0.8 1.5)
			(layers "F.Cu" "F.Mask" "F.Paste")
			(net "NetTP8_1")
		)
		(pad "20" smd rect
			(at 17.1 -6.35)
			(size 0.8 1.5)
			(layers "F.Cu" "F.Mask" "F.Paste")
		)
		(pad "21" smd rect
			(at 17.1 -7.45)
			(size 0.8 1.5)
			(layers "F.Cu" "F.Mask" "F.Paste")
		)
		(pad "22" smd rect
			(at 17.1 -8.55)
			(size 0.8 1.5)
			(layers "F.Cu" "F.Mask" "F.Paste")
		)
		(pad "23" smd rect
			(at 17.1 -9.65)
			(size 0.8 1.5)
			(layers "F.Cu" "F.Mask" "F.Paste")
		)
		(pad "24" smd rect
			(at 17.1 -10.75)
			(size 0.8 1.5)
			(layers "F.Cu" "F.Mask" "F.Paste")
		)
		(pad "25" smd rect
			(at 17.1 -11.85)
			(size 0.8 1.5)
			(layers "F.Cu" "F.Mask" "F.Paste")
		)
		(pad "26" smd rect
			(at 17.1 -12.95)
			(size 0.8 1.5)
			(layers "F.Cu" "F.Mask" "F.Paste")
			(net "NetTP7_1")
		)
		(pad "27" smd rect
			(at 17.1 -14.05)
			(size 0.8 1.5)
			(layers "F.Cu" "F.Mask" "F.Paste")
			(net "NetTP6_1")
		)
		(pad "28" smd rect
			(at 14.3 -14.9 270)
			(size 0.8 1.5)
			(layers "F.Cu" "F.Mask" "F.Paste")
		)
		(pad "29" smd rect
			(at 13.2 -14.9 270)
			(size 0.8 1.5)
			(layers "F.Cu" "F.Mask" "F.Paste")
		)
		(pad "30" smd rect
			(at 12.1 -14.9 270)
			(size 0.8 1.5)
			(layers "F.Cu" "F.Mask" "F.Paste")
		)
		(pad "31" smd rect
			(at 11 -14.9 270)
			(size 0.8 1.5)
			(layers "F.Cu" "F.Mask" "F.Paste")
		)
		(pad "32" smd rect
			(at 9.9 -14.9 270)
			(size 0.8 1.5)
			(layers "F.Cu" "F.Mask" "F.Paste")
			(net "GND")
		)
		(pad "33" smd rect
			(at 8.8 -14.9 270)
			(size 0.8 1.5)
			(layers "F.Cu" "F.Mask" "F.Paste")
			(net "VCC")
		)
		(pad "34" smd rect
			(at 7.7 -14.9 270)
			(size 0.8 1.5)
			(layers "F.Cu" "F.Mask" "F.Paste")
			(net "VCC")
		)
		(pad "35" smd rect
			(at 6.6 -14.9 270)
			(size 0.8 1.5)
			(layers "F.Cu" "F.Mask" "F.Paste")
		)
		(pad "36" smd rect
			(at 5.5 -14.9 270)
			(size 0.8 1.5)
			(layers "F.Cu" "F.Mask" "F.Paste")
			(net "VCC")
		)
		(pad "37" smd rect
			(at 4.4 -14.9 270)
			(size 0.8 1.5)
			(layers "F.Cu" "F.Mask" "F.Paste")
			(net "GND")
		)
		(pad "38" smd rect
			(at 3.3 -14.9 270)
			(size 0.8 1.5)
			(layers "F.Cu" "F.Mask" "F.Paste")
			(net "GND")
		)
		(pad "39" smd rect
			(at 2.2 -14.9 270)
			(size 0.8 1.5)
			(layers "F.Cu" "F.Mask" "F.Paste")
		)
		(pad "40" smd rect
			(at 1.1 -14.9 270)
			(size 0.8 1.5)
			(layers "F.Cu" "F.Mask" "F.Paste")
		)
		(pad "41" smd rect
			(at 0 -14.9 270)
			(size 0.8 1.5)
			(layers "F.Cu" "F.Mask" "F.Paste")
			(net "GND")
		)
		(pad "42" smd rect
			(at -2.8 -14.05)
			(size 0.8 1.5)
			(layers "F.Cu" "F.Mask" "F.Paste")
			(net "TXD")
		)
		(pad "43" smd rect
			(at -2.8 -12.95)
			(size 0.8 1.5)
			(layers "F.Cu" "F.Mask" "F.Paste")
			(net "RXD")
		)
		(pad "44" smd rect
			(at -2.8 -11.85)
			(size 0.8 1.5)
			(layers "F.Cu" "F.Mask" "F.Paste")
			(net "NetTP4_1")
		)
		(pad "45" smd rect
			(at -2.8 -10.75)
			(size 0.8 1.5)
			(layers "F.Cu" "F.Mask" "F.Paste")
			(net "NetTP5_1")
		)
		(pad "46" smd rect
			(at -2.8 -9.65)
			(size 0.8 1.5)
			(layers "F.Cu" "F.Mask" "F.Paste")
		)
		(pad "47" smd rect
			(at -2.8 -8.55)
			(size 0.8 1.5)
			(layers "F.Cu" "F.Mask" "F.Paste")
			(net "NetC5_1")
		)
		(pad "48" smd rect
			(at -2.8 -7.45)
			(size 0.8 1.5)
			(layers "F.Cu" "F.Mask" "F.Paste")
			(net "GND")
		)
		(pad "49" smd rect
			(at -2.8 -6.35)
			(size 0.8 1.5)
			(layers "F.Cu" "F.Mask" "F.Paste")
			(net "RST")
		)
		(pad "50" smd rect
			(at -2.8 -5.25)
			(size 0.8 1.5)
			(layers "F.Cu" "F.Mask" "F.Paste")
			(net "NetTP1_1")
		)
		(pad "51" smd rect
			(at -2.8 -4.15)
			(size 0.8 1.5)
			(layers "F.Cu" "F.Mask" "F.Paste")
			(net "NetTP2_1")
		)
		(pad "52" smd rect
			(at -2.8 -3.05)
			(size 0.8 1.5)
			(layers "F.Cu" "F.Mask" "F.Paste")
			(net "NetTP3_1")
		)
		(pad "53" smd rect
			(at -2.8 -1.95)
			(size 0.8 1.5)
			(layers "F.Cu" "F.Mask" "F.Paste")
			(net "TP1")
		)
		(pad "54" smd rect
			(at -2.8 -0.85)
			(size 0.8 1.5)
			(layers "F.Cu" "F.Mask" "F.Paste")
			(net "TP2")
		)
		(pad "55" smd rect
			(at -0.2 -12.69998 270)
			(size 1.1 1.1)
			(layers "F.Cu" "F.Mask" "F.Paste")
			(net "GND")
		)
		(pad "55" smd rect
			(at -0.2 -10.59998 270)
			(size 1.1 1.1)
			(layers "F.Cu" "F.Mask" "F.Paste")
			(net "GND")
		)
		(pad "55" smd rect
			(at -0.2 -8.49998 270)
			(size 1.1 1.1)
			(layers "F.Cu" "F.Mask" "F.Paste")
			(net "GND")
		)
		(pad "55" smd rect
			(at -0.2 -6.39999 270)
			(size 1.1 1.1)
			(layers "F.Cu" "F.Mask" "F.Paste")
			(net "GND")
		)
		(pad "55" smd rect
			(at -0.2 -4.29999 270)
			(size 1.1 1.1)
			(layers "F.Cu" "F.Mask" "F.Paste")
			(net "GND")
		)
		(pad "55" smd rect
			(at -0.2 -2.2 270)
			(size 1.1 1.1)
			(layers "F.Cu" "F.Mask" "F.Paste")
			(net "GND")
		)
		(pad "55" smd rect
			(at 1.9 -12.69997 270)
			(size 1.1 1.1)
			(layers "F.Cu" "F.Mask" "F.Paste")
			(net "GND")
		)
		(pad "55" smd rect
			(at 1.9 -10.59998 270)
			(size 1.1 1.1)
			(layers "F.Cu" "F.Mask" "F.Paste")
			(net "GND")
		)
		(pad "55" smd rect
			(at 1.9 -8.49998 270)
			(size 1.1 1.1)
			(layers "F.Cu" "F.Mask" "F.Paste")
			(net "GND")
		)
		(pad "55" smd rect
			(at 1.9 -6.39998 270)
			(size 1.1 1.1)
			(layers "F.Cu" "F.Mask" "F.Paste")
			(net "GND")
		)
		(pad "55" smd rect
			(at 1.9 -4.29999 270)
			(size 1.1 1.1)
			(layers "F.Cu" "F.Mask" "F.Paste")
			(net "GND")
		)
		(pad "55" smd rect
			(at 1.9 -2.19999 270)
			(size 1.1 1.1)
			(layers "F.Cu" "F.Mask" "F.Paste")
			(net "GND")
		)
		(pad "55" smd rect
			(at 4 -12.69997 270)
			(size 1.1 1.1)
			(layers "F.Cu" "F.Mask" "F.Paste")
			(net "GND")
		)
		(pad "55" smd rect
			(at 4 -10.59998 270)
			(size 1.1 1.1)
			(layers "F.Cu" "F.Mask" "F.Paste")
			(net "GND")
		)
		(pad "55" smd rect
			(at 4 -8.49998 270)
			(size 1.1 1.1)
			(layers "F.Cu" "F.Mask" "F.Paste")
			(net "GND")
		)
		(pad "55" smd rect
			(at 4 -6.39998 270)
			(size 1.1 1.1)
			(layers "F.Cu" "F.Mask" "F.Paste")
			(net "GND")
		)
		(pad "55" smd rect
			(at 4 -4.29999 270)
			(size 1.1 1.1)
			(layers "F.Cu" "F.Mask" "F.Paste")
			(net "GND")
		)
		(pad "55" smd rect
			(at 4 -2.19999 270)
			(size 1.1 1.1)
			(layers "F.Cu" "F.Mask" "F.Paste")
			(net "GND")
		)
		(pad "55" smd rect
			(at 6.1 -12.69997 270)
			(size 1.1 1.1)
			(layers "F.Cu" "F.Mask" "F.Paste")
			(net "GND")
		)
		(pad "55" smd rect
			(at 6.1 -10.59998 270)
			(size 1.1 1.1)
			(layers "F.Cu" "F.Mask" "F.Paste")
			(net "GND")
		)
		(pad "55" smd rect
			(at 6.1 -8.49998 270)
			(size 1.1 1.1)
			(layers "F.Cu" "F.Mask" "F.Paste")
			(net "GND")
		)
		(pad "55" smd rect
			(at 6.1 -6.39998 270)
			(size 1.1 1.1)
			(layers "F.Cu" "F.Mask" "F.Paste")
			(net "GND")
		)
		(pad "55" smd rect
			(at 6.1 -4.29999 270)
			(size 1.1 1.1)
			(layers "F.Cu" "F.Mask" "F.Paste")
			(net "GND")
		)
		(pad "55" smd rect
			(at 6.1 -2.19999 270)
			(size 1.1 1.1)
			(layers "F.Cu" "F.Mask" "F.Paste")
			(net "GND")
		)
		(pad "55" smd rect
			(at 8.2 -12.69997 270)
			(size 1.1 1.1)
			(layers "F.Cu" "F.Mask" "F.Paste")
			(net "GND")
		)
		(pad "55" smd rect
			(at 8.2 -10.59998 270)
			(size 1.1 1.1)
			(layers "F.Cu" "F.Mask" "F.Paste")
			(net "GND")
		)
		(pad "55" smd rect
			(at 8.2 -8.49998 270)
			(size 1.1 1.1)
			(layers "F.Cu" "F.Mask" "F.Paste")
			(net "GND")
		)
		(pad "55" smd rect
			(at 8.2 -6.39998 270)
			(size 1.1 1.1)
			(layers "F.Cu" "F.Mask" "F.Paste")
			(net "GND")
		)
		(pad "55" smd rect
			(at 8.2 -4.29999 270)
			(size 1.1 1.1)
			(layers "F.Cu" "F.Mask" "F.Paste")
			(net "GND")
		)
		(pad "55" smd rect
			(at 8.2 -2.19999 270)
			(size 1.1 1.1)
			(layers "F.Cu" "F.Mask" "F.Paste")
			(net "GND")
		)
		(pad "55" smd rect
			(at 10.3 -12.69997 270)
			(size 1.1 1.1)
			(layers "F.Cu" "F.Mask" "F.Paste")
			(net "GND")
		)
		(pad "55" smd rect
			(at 10.3 -10.59998 270)
			(size 1.1 1.1)
			(layers "F.Cu" "F.Mask" "F.Paste")
			(net "GND")
		)
		(pad "55" smd rect
			(at 10.3 -8.49998 270)
			(size 1.1 1.1)
			(layers "F.Cu" "F.Mask" "F.Paste")
			(net "GND")
		)
		(pad "55" smd rect
			(at 10.3 -6.39998 270)
			(size 1.1 1.1)
			(layers "F.Cu" "F.Mask" "F.Paste")
			(net "GND")
		)
		(pad "55" smd rect
			(at 10.3 -4.29999 270)
			(size 1.1 1.1)
			(layers "F.Cu" "F.Mask" "F.Paste")
			(net "GND")
		)
		(pad "55" smd rect
			(at 10.3 -2.19999 270)
			(size 1.1 1.1)
			(layers "F.Cu" "F.Mask" "F.Paste")
			(net "GND")
		)
		(pad "55" smd rect
			(at 12.4 -12.69997 270)
			(size 1.1 1.1)
			(layers "F.Cu" "F.Mask" "F.Paste")
			(net "GND")
		)
		(pad "55" smd rect
			(at 12.4 -10.59998 270)
			(size 1.1 1.1)
			(layers "F.Cu" "F.Mask" "F.Paste")
			(net "GND")
		)
		(pad "55" smd rect
			(at 12.4 -8.49998 270)
			(size 1.1 1.1)
			(layers "F.Cu" "F.Mask" "F.Paste")
			(net "GND")
		)
		(pad "55" smd rect
			(at 12.4 -6.39998 270)
			(size 1.1 1.1)
			(layers "F.Cu" "F.Mask" "F.Paste")
			(net "GND")
		)
		(pad "55" smd rect
			(at 12.4 -4.29999 270)
			(size 1.1 1.1)
			(layers "F.Cu" "F.Mask" "F.Paste")
			(net "GND")
		)
		(pad "55" smd rect
			(at 12.4 -2.19999 270)
			(size 1.1 1.1)
			(layers "F.Cu" "F.Mask" "F.Paste")
			(net "GND")
		)
		(pad "55" smd rect
			(at 14.5 -12.69997 270)
			(size 1.1 1.1)
			(layers "F.Cu" "F.Mask" "F.Paste")
			(net "GND")
		)
		(pad "55" smd rect
			(at 14.5 -10.59998 270)
			(size 1.1 1.1)
			(layers "F.Cu" "F.Mask" "F.Paste")
			(net "GND")
		)
		(pad "55" smd rect
			(at 14.5 -8.49998 270)
			(size 1.1 1.1)
			(layers "F.Cu" "F.Mask" "F.Paste")
			(net "GND")
		)
		(pad "55" smd rect
			(at 14.5 -6.39998 270)
			(size 1.1 1.1)
			(layers "F.Cu" "F.Mask" "F.Paste")
			(net "GND")
		)
		(pad "55" smd rect
			(at 14.5 -4.29999 270)
			(size 1.1 1.1)
			(layers "F.Cu" "F.Mask" "F.Paste")
			(net "GND")
		)
		(pad "55" smd rect
			(at 14.5 -2.19999 270)
			(size 1.1 1.1)
			(layers "F.Cu" "F.Mask" "F.Paste")
			(net "GND")
		)
	)
	(footprint "Vault:TP001V_SMT_100DIA"
		(layer "F.Cu")
		(at 156.4441 118.4631 90)
		(property "Reference" "TP6"
			(at 4.0108 0.07907 90)
			(unlocked yes)
			(layer "F.SilkS")
			(effects
				(font
					(size 0.8 0.8)
					(thickness 0.15)
				)
			)
		)
		(property "Value" "SMT_100DIA"
			(at -2.124202 7.0716 0)
			(unlocked yes)
			(layer "F.SilkS")
			(hide yes)
			(effects
				(font
					(size 1.524 1.524)
					(thickness 0.254)
				)
			)
		)
		(sheetname "ZED-F9T")
		(sheetfile "ZED-F9T.kicad_sch")
		(duplicate_pad_numbers_are_jumpers no)
		(pad "1" smd circle
			(at 1.397 0 90)
			(size 1 1)
			(layers "F.Cu" "F.Mask" "F.Paste")
			(net "NetTP6_1")
			(solder_mask_margin 0.05)
			(solder_paste_margin 0)
			(thermal_bridge_angle 90)
		)
	)
)
